# T6G (Grand Teton) — schematic netlist excerpt (pin names and nets, part order shuffled) for the footprints in the layout excerpt that follows; sources: Cadence DE-HDL packaged netlist, KiCad conversion of 04192023_DAF0TMB3IC0_F0TG_MB_C_brd_V02_OCP.brd

PR495  Q_RES  1.5 1% EMPTY  pkg 0402LF  page 194 : A = SW_PVDDCR_CPU0_P0_SW1_RC ; B = GND
R1313  Q_RES  4.7K 5% CHIP  pkg 0402LF  page 171 : A = PD_U160_EN_N ; B = GND

(kicad_pcb
	(version 20260206)
	(generator "pcbnew")
	(generator_version "10.0")
	(general
		(thickness 1.6)
		(legacy_teardrops no)
	)
	(paper "A4")
	(title_block
		(title "04192023_DAF0TMB3IC0_F0TG_MB_C_brd_V02_OCP.brd")
		(comment 1 "Grand Teton / footprints 2116-2117 of 8354")
	)
	(layers
		(0 "F.Cu" signal "TOP")
		(4 "In1.Cu" signal "GND")
		(6 "In2.Cu" signal "IN1")
		(8 "In3.Cu" signal "GND1")
		(10 "In4.Cu" signal "IN2")
		(12 "In5.Cu" signal "GND2")
		(14 "In6.Cu" signal "IN3")
		(16 "In7.Cu" signal "GND3")
		(18 "In8.Cu" signal "VCC")
		(20 "In9.Cu" signal "VCC1")
		(22 "In10.Cu" signal "GND4")
		(24 "In11.Cu" signal "IN4")
		(26 "In12.Cu" signal "GND5")
		(28 "In13.Cu" signal "IN5")
		(30 "In14.Cu" signal "GND6")
		(32 "In15.Cu" signal "IN6")
		(34 "In16.Cu" signal "GND7")
		(2 "B.Cu" signal "BOTTOM")
		(9 "F.Adhes" user "F.Adhesive")
		(11 "B.Adhes" user "B.Adhesive")
		(13 "F.Paste" user "Package Geometry/Pastemask Top")
		(15 "B.Paste" user "Package Geometry/Pastemask Bottom")
		(5 "F.SilkS" user "Ref Des/Silkscreen Top")
		(7 "B.SilkS" user "Ref Des/Silkscreen Bottom")
		(1 "F.Mask" user "Board Geometry/Soldermask Top")
		(3 "B.Mask" user "Board Geometry/Soldermask Bottom")
		(17 "Dwgs.User" user "User.Drawings")
		(19 "Cmts.User" user "User.Comments")
		(21 "Eco1.User" user "User.Eco1")
		(23 "Eco2.User" user "User.Eco2")
		(25 "Edge.Cuts" user "Board Geometry/Outline")
		(27 "Margin" user)
		(31 "F.CrtYd" user "Package Geometry/Place Bound Top")
		(29 "B.CrtYd" user "Package Geometry/Place Bound Bottom")
		(35 "F.Fab" user "Ref Des/Assembly Top")
		(33 "B.Fab" user "Ref Des/Assembly Bottom")
	)
	(footprint ""
		(layer "F.Cu")
		(at 30.484064 -80.424274 90)
		(property "Reference" "R1313"
			(at 0 0 90)
			(layer "F.SilkS")
			(hide yes)
			(effects
				(font
					(size 1.27 1.27)
				)
			)
		)
		(property "Value" ""
			(at 0 0 90)
			(layer "F.Fab")
			(effects
				(font
					(size 1.27 1.27)
				)
			)
		)
		(duplicate_pad_numbers_are_jumpers no)
		(fp_line
			(start 0.7874 -0.4064)
			(end 0.7874 0.4064)
			(stroke
				(width 0.1524)
				(type default)
			)
			(layer "F.SilkS")
		)
		(fp_line
			(start -0.7874 -0.4064)
			(end 0.7874 -0.4064)
			(stroke
				(width 0.1524)
				(type default)
			)
			(layer "F.SilkS")
		)
		(fp_line
			(start 0.7874 0.4064)
			(end -0.7874 0.4064)
			(stroke
				(width 0.1524)
				(type default)
			)
			(layer "F.SilkS")
		)
		(fp_line
			(start -0.7874 0.4064)
			(end -0.7874 -0.4064)
			(stroke
				(width 0.1524)
				(type default)
			)
			(layer "F.SilkS")
		)
		(fp_line
			(start -0.12065 -0.305054)
			(end -0.12065 -0.2794)
			(stroke
				(width 0.1)
				(type default)
			)
			(layer "F.Fab")
		)
		(fp_line
			(start -0.67945 -0.305054)
			(end -0.12065 -0.305054)
			(stroke
				(width 0.1)
				(type default)
			)
			(layer "F.Fab")
		)
		(fp_line
			(start 0.67945 -0.3048)
			(end 0.67945 0.3048)
			(stroke
				(width 0.1)
				(type default)
			)
			(layer "F.Fab")
		)
		(fp_line
			(start 0.12065 -0.3048)
			(end 0.67945 -0.3048)
			(stroke
				(width 0.1)
				(type default)
			)
			(layer "F.Fab")
		)
		(fp_line
			(start 0.12065 -0.2794)
			(end 0.12065 -0.3048)
			(stroke
				(width 0.1)
				(type default)
			)
			(layer "F.Fab")
		)
		(fp_line
			(start -0.12065 -0.2794)
			(end 0.12065 -0.2794)
			(stroke
				(width 0.1)
				(type default)
			)
			(layer "F.Fab")
		)
		(fp_line
			(start 0.120396 0.2794)
			(end -0.12065 0.2794)
			(stroke
				(width 0.1)
				(type default)
			)
			(layer "F.Fab")
		)
		(fp_line
			(start -0.12065 0.2794)
			(end -0.12065 0.3048)
			(stroke
				(width 0.1)
				(type default)
			)
			(layer "F.Fab")
		)
		(fp_line
			(start 0.67945 0.3048)
			(end 0.120396 0.3048)
			(stroke
				(width 0.1)
				(type default)
			)
			(layer "F.Fab")
		)
		(fp_line
			(start 0.120396 0.3048)
			(end 0.120396 0.2794)
			(stroke
				(width 0.1)
				(type default)
			)
			(layer "F.Fab")
		)
		(fp_line
			(start -0.12065 0.3048)
			(end -0.67945 0.3048)
			(stroke
				(width 0.1)
				(type default)
			)
			(layer "F.Fab")
		)
		(fp_line
			(start -0.67945 0.3048)
			(end -0.67945 -0.305054)
			(stroke
				(width 0.1)
				(type default)
			)
			(layer "F.Fab")
		)
		(pad "1" smd circle
			(at -0.40005 0 90)
			(size 0 0)
			(layers "F.Cu" "F.Mask" "F.Paste")
			(net "PD_U160_EN_N")
		)
		(pad "2" smd circle
			(at 0.40005 0 90)
			(size 0 0)
			(layers "F.Cu" "F.Mask" "F.Paste")
			(net "GND")
		)
	)
	(footprint ""
		(layer "F.Cu")
		(at 367.991136 -179.50561 -90)
		(property "Reference" "PR495"
			(at 0 0 270)
			(layer "F.SilkS")
			(hide yes)
			(effects
				(font
					(size 1.27 1.27)
				)
			)
		)
		(property "Value" ""
			(at 0 0 270)
			(layer "F.Fab")
			(effects
				(font
					(size 1.27 1.27)
				)
			)
		)
		(duplicate_pad_numbers_are_jumpers no)
		(fp_line
			(start -0.7874 0.4064)
			(end -0.7874 -0.4064)
			(stroke
				(width 0.1524)
				(type default)
			)
			(layer "F.SilkS")
		)
		(fp_line
			(start 0.7874 0.4064)
			(end -0.7874 0.4064)
			(stroke
				(width 0.1524)
				(type default)
			)
			(layer "F.SilkS")
		)
		(fp_line
			(start -0.7874 -0.4064)
			(end 0.7874 -0.4064)
			(stroke
				(width 0.1524)
				(type default)
			)
			(layer "F.SilkS")
		)
		(fp_line
			(start 0.7874 -0.4064)
			(end 0.7874 0.4064)
			(stroke
				(width 0.1524)
				(type default)
			)
			(layer "F.SilkS")
		)
		(fp_line
			(start -0.67945 0.3048)
			(end -0.67945 -0.305054)
			(stroke
				(width 0.1)
				(type default)
			)
			(layer "F.Fab")
		)
		(fp_line
			(start -0.12065 0.3048)
			(end -0.67945 0.3048)
			(stroke
				(width 0.1)
				(type default)
			)
			(layer "F.Fab")
		)
		(fp_line
			(start 0.120396 0.3048)
			(end 0.120396 0.2794)
			(stroke
				(width 0.1)
				(type default)
			)
			(layer "F.Fab")
		)
		(fp_line
			(start 0.67945 0.3048)
			(end 0.120396 0.3048)
			(stroke
				(width 0.1)
				(type default)
			)
			(layer "F.Fab")
		)
		(fp_line
			(start -0.12065 0.2794)
			(end -0.12065 0.3048)
			(stroke
				(width 0.1)
				(type default)
			)
			(layer "F.Fab")
		)
		(fp_line
			(start 0.120396 0.2794)
			(end -0.12065 0.2794)
			(stroke
				(width 0.1)
				(type default)
			)
			(layer "F.Fab")
		)
		(fp_line
			(start -0.12065 -0.2794)
			(end 0.12065 -0.2794)
			(stroke
				(width 0.1)
				(type default)
			)
			(layer "F.Fab")
		)
		(fp_line
			(start 0.12065 -0.2794)
			(end 0.12065 -0.3048)
			(stroke
				(width 0.1)
				(type default)
			)
			(layer "F.Fab")
		)
		(fp_line
			(start 0.12065 -0.3048)
			(end 0.67945 -0.3048)
			(stroke
				(width 0.1)
				(type default)
			)
			(layer "F.Fab")
		)
		(fp_line
			(start 0.67945 -0.3048)
			(end 0.67945 0.3048)
			(stroke
				(width 0.1)
				(type default)
			)
			(layer "F.Fab")
		)
		(fp_line
			(start -0.67945 -0.305054)
			(end -0.12065 -0.305054)
			(stroke
				(width 0.1)
				(type default)
			)
			(layer "F.Fab")
		)
		(fp_line
			(start -0.12065 -0.305054)
			(end -0.12065 -0.2794)
			(stroke
				(width 0.1)
				(type default)
			)
			(layer "F.Fab")
		)
		(pad "1" smd circle
			(at -0.40005 0 270)
			(size 0 0)
			(layers "F.Cu" "F.Mask" "F.Paste")
			(net "SW_PVDDCR_CPU0_P0_SW1_RC")
		)
		(pad "2" smd circle
			(at 0.40005 0 270)
			(size 0 0)
			(layers "F.Cu" "F.Mask" "F.Paste")
			(net "GND")
		)
	)
)
